(kicad_pcb
	(version 20260206)
	(generator "pcbnew")
	(generator_version "10.0")
	(general
		(thickness 1.6)
		(legacy_teardrops no)
	)
	(paper "A4")
	(title_block
		(title "01162023_DA0F0TEBIF0_F0T_Expander_BD_F_brd_V02_OCP.brd")
		(comment 1 "Grand Teton / footprints 3759-3766 of 9728")
	)
	(layers
		(0 "F.Cu" signal "TOP")
		(4 "In1.Cu" signal "GND")
		(6 "In2.Cu" signal "VCC")
		(8 "In3.Cu" signal "VCC1")
		(10 "In4.Cu" signal "GND1")
		(12 "In5.Cu" signal "IN1")
		(14 "In6.Cu" signal "GND2")
		(16 "In7.Cu" signal "IN2")
		(18 "In8.Cu" signal "GND3")
		(20 "In9.Cu" signal "IN3")
		(22 "In10.Cu" signal "GND4")
		(24 "In11.Cu" signal "IN4")
		(26 "In12.Cu" signal "GND5")
		(28 "In13.Cu" signal "IN5")
		(30 "In14.Cu" signal "GND6")
		(32 "In15.Cu" signal "IN6")
		(34 "In16.Cu" signal "GND7")
		(2 "B.Cu" signal "BOTTOM")
		(9 "F.Adhes" user "F.Adhesive")
		(11 "B.Adhes" user "B.Adhesive")
		(13 "F.Paste" user "Package Geometry/Pastemask Top")
		(15 "B.Paste" user "Package Geometry/Pastemask Bottom")
		(5 "F.SilkS" user "Ref Des/Silkscreen Top")
		(7 "B.SilkS" user "Ref Des/Silkscreen Bottom")
		(1 "F.Mask" user "Board Geometry/Soldermask Top")
		(3 "B.Mask" user "Board Geometry/Soldermask Bottom")
		(17 "Dwgs.User" user "User.Drawings")
		(19 "Cmts.User" user "User.Comments")
		(21 "Eco1.User" user "User.Eco1")
		(23 "Eco2.User" user "User.Eco2")
		(25 "Edge.Cuts" user "Board Geometry/Outline")
		(27 "Margin" user)
		(31 "F.CrtYd" user "Package Geometry/Place Bound Top")
		(29 "B.CrtYd" user "Package Geometry/Place Bound Bottom")
		(35 "F.Fab" user "Ref Des/Assembly Top")
		(33 "B.Fab" user "Ref Des/Assembly Bottom")
	)
	(footprint ""
		(layer "F.Cu")
		(at 213.801198 -220.322902)
		(property "Reference" "R4874"
			(at 0 0 0)
			(layer "F.SilkS")
			(hide yes)
			(effects
				(font
					(size 1.27 1.27)
				)
			)
		)
		(property "Value" ""
			(at 0 0 0)
			(layer "F.Fab")
			(effects
				(font
					(size 1.27 1.27)
				)
			)
		)
		(duplicate_pad_numbers_are_jumpers no)
		(fp_line
			(start -0.7874 -0.4064)
			(end 0.7874 -0.4064)
			(stroke
				(width 0.1524)
				(type default)
			)
			(layer "F.SilkS")
		)
		(fp_line
			(start -0.7874 0.4064)
			(end -0.7874 -0.4064)
			(stroke
				(width 0.1524)
				(type default)
			)
			(layer "F.SilkS")
		)
		(fp_line
			(start 0.7874 -0.4064)
			(end 0.7874 0.4064)
			(stroke
				(width 0.1524)
				(type default)
			)
			(layer "F.SilkS")
		)
		(fp_line
			(start 0.7874 0.4064)
			(end -0.7874 0.4064)
			(stroke
				(width 0.1524)
				(type default)
			)
			(layer "F.SilkS")
		)
		(fp_line
			(start -0.67945 -0.305054)
			(end -0.12065 -0.305054)
			(stroke
				(width 0.1)
				(type default)
			)
			(layer "F.Fab")
		)
		(fp_line
			(start -0.67945 0.3048)
			(end -0.67945 -0.305054)
			(stroke
				(width 0.1)
				(type default)
			)
			(layer "F.Fab")
		)
		(fp_line
			(start -0.12065 -0.305054)
			(end -0.12065 -0.2794)
			(stroke
				(width 0.1)
				(type default)
			)
			(layer "F.Fab")
		)
		(fp_line
			(start -0.12065 -0.2794)
			(end 0.12065 -0.2794)
			(stroke
				(width 0.1)
				(type default)
			)
			(layer "F.Fab")
		)
		(fp_line
			(start -0.12065 0.2794)
			(end -0.12065 0.3048)
			(stroke
				(width 0.1)
				(type default)
			)
			(layer "F.Fab")
		)
		(fp_line
			(start -0.12065 0.3048)
			(end -0.67945 0.3048)
			(stroke
				(width 0.1)
				(type default)
			)
			(layer "F.Fab")
		)
		(fp_line
			(start 0.120396 0.2794)
			(end -0.12065 0.2794)
			(stroke
				(width 0.1)
				(type default)
			)
			(layer "F.Fab")
		)
		(fp_line
			(start 0.120396 0.3048)
			(end 0.120396 0.2794)
			(stroke
				(width 0.1)
				(type default)
			)
			(layer "F.Fab")
		)
		(fp_line
			(start 0.12065 -0.3048)
			(end 0.67945 -0.3048)
			(stroke
				(width 0.1)
				(type default)
			)
			(layer "F.Fab")
		)
		(fp_line
			(start 0.12065 -0.2794)
			(end 0.12065 -0.3048)
			(stroke
				(width 0.1)
				(type default)
			)
			(layer "F.Fab")
		)
		(fp_line
			(start 0.67945 -0.3048)
			(end 0.67945 0.3048)
			(stroke
				(width 0.1)
				(type default)
			)
			(layer "F.Fab")
		)
		(fp_line
			(start 0.67945 0.3048)
			(end 0.120396 0.3048)
			(stroke
				(width 0.1)
				(type default)
			)
			(layer "F.Fab")
		)
		(pad "1" smd circle
			(at -0.40005 0)
			(size 0 0)
			(layers "F.Cu" "F.Mask" "F.Paste")
			(net "P1V2_AUX")
		)
		(pad "2" smd circle
			(at 0.40005 0)
			(size 0 0)
			(layers "F.Cu" "F.Mask" "F.Paste")
			(net "SMB_NIC4_SDA")
		)
	)
	(footprint ""
		(layer "F.Cu")
		(at 233.326178 -39.73576 -90)
		(property "Reference" "R5563"
			(at 0 0 270)
			(layer "F.SilkS")
			(hide yes)
			(effects
				(font
					(size 1.27 1.27)
				)
			)
		)
		(property "Value" ""
			(at 0 0 270)
			(layer "F.Fab")
			(effects
				(font
					(size 1.27 1.27)
				)
			)
		)
		(duplicate_pad_numbers_are_jumpers no)
		(fp_line
			(start -0.7874 0.4064)
			(end -0.7874 -0.4064)
			(stroke
				(width 0.1524)
				(type default)
			)
			(layer "F.SilkS")
		)
		(fp_line
			(start 0.7874 0.4064)
			(end -0.7874 0.4064)
			(stroke
				(width 0.1524)
				(type default)
			)
			(layer "F.SilkS")
		)
		(fp_line
			(start -0.7874 -0.4064)
			(end 0.7874 -0.4064)
			(stroke
				(width 0.1524)
				(type default)
			)
			(layer "F.SilkS")
		)
		(fp_line
			(start 0.7874 -0.4064)
			(end 0.7874 0.4064)
			(stroke
				(width 0.1524)
				(type default)
			)
			(layer "F.SilkS")
		)
		(fp_line
			(start -0.67945 0.3048)
			(end -0.67945 -0.305054)
			(stroke
				(width 0.1)
				(type default)
			)
			(layer "F.Fab")
		)
		(fp_line
			(start -0.12065 0.3048)
			(end -0.67945 0.3048)
			(stroke
				(width 0.1)
				(type default)
			)
			(layer "F.Fab")
		)
		(fp_line
			(start 0.120396 0.3048)
			(end 0.120396 0.2794)
			(stroke
				(width 0.1)
				(type default)
			)
			(layer "F.Fab")
		)
		(fp_line
			(start 0.67945 0.3048)
			(end 0.120396 0.3048)
			(stroke
				(width 0.1)
				(type default)
			)
			(layer "F.Fab")
		)
		(fp_line
			(start -0.12065 0.2794)
			(end -0.12065 0.3048)
			(stroke
				(width 0.1)
				(type default)
			)
			(layer "F.Fab")
		)
		(fp_line
			(start 0.120396 0.2794)
			(end -0.12065 0.2794)
			(stroke
				(width 0.1)
				(type default)
			)
			(layer "F.Fab")
		)
		(fp_line
			(start -0.12065 -0.2794)
			(end 0.12065 -0.2794)
			(stroke
				(width 0.1)
				(type default)
			)
			(layer "F.Fab")
		)
		(fp_line
			(start 0.12065 -0.2794)
			(end 0.12065 -0.3048)
			(stroke
				(width 0.1)
				(type default)
			)
			(layer "F.Fab")
		)
		(fp_line
			(start 0.12065 -0.3048)
			(end 0.67945 -0.3048)
			(stroke
				(width 0.1)
				(type default)
			)
			(layer "F.Fab")
		)
		(fp_line
			(start 0.67945 -0.3048)
			(end 0.67945 0.3048)
			(stroke
				(width 0.1)
				(type default)
			)
			(layer "F.Fab")
		)
		(fp_line
			(start -0.67945 -0.305054)
			(end -0.12065 -0.305054)
			(stroke
				(width 0.1)
				(type default)
			)
			(layer "F.Fab")
		)
		(fp_line
			(start -0.12065 -0.305054)
			(end -0.12065 -0.2794)
			(stroke
				(width 0.1)
				(type default)
			)
			(layer "F.Fab")
		)
		(pad "1" smd circle
			(at -0.40005 0 270)
			(size 0 0)
			(layers "F.Cu" "F.Mask" "F.Paste")
			(net "P3V3_AUX")
		)
		(pad "2" smd circle
			(at 0.40005 0 270)
			(size 0 0)
			(layers "F.Cu" "F.Mask" "F.Paste")
			(net "SSD8_AUX_P3V3_EN")
		)
	)
	(footprint ""
		(layer "F.Cu")
		(at 138.363452 -146.592798 -90)
		(property "Reference" "R711"
			(at 0 0 270)
			(layer "F.SilkS")
			(hide yes)
			(effects
				(font
					(size 1.27 1.27)
				)
			)
		)
		(property "Value" ""
			(at 0 0 270)
			(layer "F.Fab")
			(effects
				(font
					(size 1.27 1.27)
				)
			)
		)
		(duplicate_pad_numbers_are_jumpers no)
		(fp_line
			(start -0.7874 0.4064)
			(end -0.7874 -0.4064)
			(stroke
				(width 0.1524)
				(type default)
			)
			(layer "F.SilkS")
		)
		(fp_line
			(start 0.7874 0.4064)
			(end -0.7874 0.4064)
			(stroke
				(width 0.1524)
				(type default)
			)
			(layer "F.SilkS")
		)
		(fp_line
			(start -0.7874 -0.4064)
			(end 0.7874 -0.4064)
			(stroke
				(width 0.1524)
				(type default)
			)
			(layer "F.SilkS")
		)
		(fp_line
			(start 0.7874 -0.4064)
			(end 0.7874 0.4064)
			(stroke
				(width 0.1524)
				(type default)
			)
			(layer "F.SilkS")
		)
		(fp_line
			(start -0.67945 0.3048)
			(end -0.67945 -0.305054)
			(stroke
				(width 0.1)
				(type default)
			)
			(layer "F.Fab")
		)
		(fp_line
			(start -0.12065 0.3048)
			(end -0.67945 0.3048)
			(stroke
				(width 0.1)
				(type default)
			)
			(layer "F.Fab")
		)
		(fp_line
			(start 0.120396 0.3048)
			(end 0.120396 0.2794)
			(stroke
				(width 0.1)
				(type default)
			)
			(layer "F.Fab")
		)
		(fp_line
			(start 0.67945 0.3048)
			(end 0.120396 0.3048)
			(stroke
				(width 0.1)
				(type default)
			)
			(layer "F.Fab")
		)
		(fp_line
			(start -0.12065 0.2794)
			(end -0.12065 0.3048)
			(stroke
				(width 0.1)
				(type default)
			)
			(layer "F.Fab")
		)
		(fp_line
			(start 0.120396 0.2794)
			(end -0.12065 0.2794)
			(stroke
				(width 0.1)
				(type default)
			)
			(layer "F.Fab")
		)
		(fp_line
			(start -0.12065 -0.2794)
			(end 0.12065 -0.2794)
			(stroke
				(width 0.1)
				(type default)
			)
			(layer "F.Fab")
		)
		(fp_line
			(start 0.12065 -0.2794)
			(end 0.12065 -0.3048)
			(stroke
				(width 0.1)
				(type default)
			)
			(layer "F.Fab")
		)
		(fp_line
			(start 0.12065 -0.3048)
			(end 0.67945 -0.3048)
			(stroke
				(width 0.1)
				(type default)
			)
			(layer "F.Fab")
		)
		(fp_line
			(start 0.67945 -0.3048)
			(end 0.67945 0.3048)
			(stroke
				(width 0.1)
				(type default)
			)
			(layer "F.Fab")
		)
		(fp_line
			(start -0.67945 -0.305054)
			(end -0.12065 -0.305054)
			(stroke
				(width 0.1)
				(type default)
			)
			(layer "F.Fab")
		)
		(fp_line
			(start -0.12065 -0.305054)
			(end -0.12065 -0.2794)
			(stroke
				(width 0.1)
				(type default)
			)
			(layer "F.Fab")
		)
		(pad "1" smd circle
			(at -0.40005 0 270)
			(size 0 0)
			(layers "F.Cu" "F.Mask" "F.Paste")
			(net "P12V_NIC2_R")
		)
		(pad "2" smd circle
			(at 0.40005 0 270)
			(size 0 0)
			(layers "F.Cu" "F.Mask" "F.Paste")
			(net "P12V_NIC2_VIN_P")
		)
	)
	(footprint ""
		(layer "F.Cu")
		(at 268.838426 -122.79884)
		(property "Reference" "C465"
			(at 0 0 0)
			(layer "F.SilkS")
			(hide yes)
			(effects
				(font
					(size 1.27 1.27)
				)
			)
		)
		(property "Value" ""
			(at 0 0 0)
			(layer "F.Fab")
			(effects
				(font
					(size 1.27 1.27)
				)
			)
		)
		(duplicate_pad_numbers_are_jumpers no)
		(fp_line
			(start -0.299974 -0.150114)
			(end 0.299974 -0.150114)
			(stroke
				(width 0.1)
				(type default)
			)
			(layer "F.Fab")
		)
		(fp_line
			(start -0.299974 0.150114)
			(end -0.299974 -0.150114)
			(stroke
				(width 0.1)
				(type default)
			)
			(layer "F.Fab")
		)
		(fp_line
			(start 0.299974 -0.150114)
			(end 0.299974 0.150114)
			(stroke
				(width 0.1)
				(type default)
			)
			(layer "F.Fab")
		)
		(fp_line
			(start 0.299974 0.150114)
			(end -0.299974 0.150114)
			(stroke
				(width 0.1)
				(type default)
			)
			(layer "F.Fab")
		)
		(pad "1" smd rect
			(at -0.2667 0)
			(size 0.3048 0.381)
			(layers "F.Cu" "F.Mask" "F.Paste")
			(net "P5E_PEX2_STN1_TX_DP<26>")
		)
		(pad "2" smd rect
			(at 0.2667 0)
			(size 0.3048 0.381)
			(layers "F.Cu" "F.Mask" "F.Paste")
			(net "P5E_PEX2_STN1_TX_C_DP<26>")
		)
	)
	(footprint ""
		(layer "F.Cu")
		(at 262.638286 -250.070874 -90)
		(property "Reference" "R1336"
			(at 0 0 270)
			(layer "F.SilkS")
			(hide yes)
			(effects
				(font
					(size 1.27 1.27)
				)
			)
		)
		(property "Value" ""
			(at 0 0 270)
			(layer "F.Fab")
			(effects
				(font
					(size 1.27 1.27)
				)
			)
		)
		(duplicate_pad_numbers_are_jumpers no)
		(fp_line
			(start -0.7874 0.4064)
			(end -0.7874 -0.4064)
			(stroke
				(width 0.1524)
				(type default)
			)
			(layer "F.SilkS")
		)
		(fp_line
			(start 0.7874 0.4064)
			(end -0.7874 0.4064)
			(stroke
				(width 0.1524)
				(type default)
			)
			(layer "F.SilkS")
		)
		(fp_line
			(start -0.7874 -0.4064)
			(end 0.7874 -0.4064)
			(stroke
				(width 0.1524)
				(type default)
			)
			(layer "F.SilkS")
		)
		(fp_line
			(start 0.7874 -0.4064)
			(end 0.7874 0.4064)
			(stroke
				(width 0.1524)
				(type default)
			)
			(layer "F.SilkS")
		)
		(fp_line
			(start -0.67945 0.3048)
			(end -0.67945 -0.305054)
			(stroke
				(width 0.1)
				(type default)
			)
			(layer "F.Fab")
		)
		(fp_line
			(start -0.12065 0.3048)
			(end -0.67945 0.3048)
			(stroke
				(width 0.1)
				(type default)
			)
			(layer "F.Fab")
		)
		(fp_line
			(start 0.120396 0.3048)
			(end 0.120396 0.2794)
			(stroke
				(width 0.1)
				(type default)
			)
			(layer "F.Fab")
		)
		(fp_line
			(start 0.67945 0.3048)
			(end 0.120396 0.3048)
			(stroke
				(width 0.1)
				(type default)
			)
			(layer "F.Fab")
		)
		(fp_line
			(start -0.12065 0.2794)
			(end -0.12065 0.3048)
			(stroke
				(width 0.1)
				(type default)
			)
			(layer "F.Fab")
		)
		(fp_line
			(start 0.120396 0.2794)
			(end -0.12065 0.2794)
			(stroke
				(width 0.1)
				(type default)
			)
			(layer "F.Fab")
		)
		(fp_line
			(start -0.12065 -0.2794)
			(end 0.12065 -0.2794)
			(stroke
				(width 0.1)
				(type default)
			)
			(layer "F.Fab")
		)
		(fp_line
			(start 0.12065 -0.2794)
			(end 0.12065 -0.3048)
			(stroke
				(width 0.1)
				(type default)
			)
			(layer "F.Fab")
		)
		(fp_line
			(start 0.12065 -0.3048)
			(end 0.67945 -0.3048)
			(stroke
				(width 0.1)
				(type default)
			)
			(layer "F.Fab")
		)
		(fp_line
			(start 0.67945 -0.3048)
			(end 0.67945 0.3048)
			(stroke
				(width 0.1)
				(type default)
			)
			(layer "F.Fab")
		)
		(fp_line
			(start -0.67945 -0.305054)
			(end -0.12065 -0.305054)
			(stroke
				(width 0.1)
				(type default)
			)
			(layer "F.Fab")
		)
		(fp_line
			(start -0.12065 -0.305054)
			(end -0.12065 -0.2794)
			(stroke
				(width 0.1)
				(type default)
			)
			(layer "F.Fab")
		)
		(pad "1" smd circle
			(at -0.40005 0 270)
			(size 0 0)
			(layers "F.Cu" "F.Mask" "F.Paste")
			(net "PEX2_MODE_SEL0")
		)
		(pad "2" smd circle
			(at 0.40005 0 270)
			(size 0 0)
			(layers "F.Cu" "F.Mask" "F.Paste")
			(net "P1V8_PEX")
		)
	)
	(footprint ""
		(layer "F.Cu")
		(at 263.85012 -50.96383 180)
		(property "Reference" "PC561"
			(at 0 0 180)
			(layer "F.SilkS")
			(hide yes)
			(effects
				(font
					(size 1.27 1.27)
				)
			)
		)
		(property "Value" ""
			(at 0 0 180)
			(layer "F.Fab")
			(effects
				(font
					(size 1.27 1.27)
				)
			)
		)
		(duplicate_pad_numbers_are_jumpers no)
		(fp_line
			(start 1.524 0.762)
			(end -1.524 0.762)
			(stroke
				(width 0.1524)
				(type default)
			)
			(layer "F.SilkS")
		)
		(fp_line
			(start 1.524 -0.762)
			(end 1.524 0.762)
			(stroke
				(width 0.1524)
				(type default)
			)
			(layer "F.SilkS")
		)
		(fp_line
			(start -1.524 0.762)
			(end -1.524 -0.762)
			(stroke
				(width 0.1524)
				(type default)
			)
			(layer "F.SilkS")
		)
		(fp_line
			(start -1.524 -0.762)
			(end 1.524 -0.762)
			(stroke
				(width 0.1524)
				(type default)
			)
			(layer "F.SilkS")
		)
		(fp_line
			(start 1.1049 0.724916)
			(end 1.1049 -0.724916)
			(stroke
				(width 0.1)
				(type default)
			)
			(layer "F.Fab")
		)
		(fp_line
			(start 1.1049 -0.724916)
			(end -1.1049 -0.724916)
			(stroke
				(width 0.1)
				(type default)
			)
			(layer "F.Fab")
		)
		(fp_line
			(start -1.1049 0.724916)
			(end 1.1049 0.724916)
			(stroke
				(width 0.1)
				(type default)
			)
			(layer "F.Fab")
		)
		(fp_line
			(start -1.1049 -0.724916)
			(end -1.1049 0.724916)
			(stroke
				(width 0.1)
				(type default)
			)
			(layer "F.Fab")
		)
		(pad "1" smd rect
			(at -0.889 0)
			(size 1.016 1.27)
			(layers "F.Cu" "F.Mask" "F.Paste")
			(net "P3V3_SSD9")
		)
		(pad "2" smd rect
			(at 0.889 0)
			(size 1.016 1.27)
			(layers "F.Cu" "F.Mask" "F.Paste")
			(net "GND")
		)
	)
	(footprint ""
		(layer "F.Cu")
		(at 478.274888 -552.440348 180)
		(property "Reference" "J42_OTH"
			(at -3.2385 -1.402334 0)
			(unlocked yes)
			(layer "B.SilkS")
			(effects
				(font
					(size 0.7874 0.5842)
					(thickness 0.1524)
				)
				(justify mirror)
			)
		)
		(property "Value" ""
			(at 0 0 180)
			(layer "F.Fab")
			(effects
				(font
					(size 1.27 1.27)
				)
			)
		)
		(duplicate_pad_numbers_are_jumpers no)
		(pad "1" thru_hole circle
			(at 0 0 180)
			(size 0.4572 0.4572)
			(drill 0.2032)
			(layers "*.Cu" "*.Mask")
			(remove_unused_layers no)
			(net "Net_9094")
			(clearance 0.127)
			(thermal_gap 0.127)
			(padstack
				(mode front_inner_back)
				(layer "Inner"
					(shape circle)
					(size 0.4572 0.4572)
					(clearance 0.127)
				)
				(layer "B.Cu"
					(shape circle)
					(size 0.508 0.508)
					(clearance 0.1016)
				)
			)
		)
	)
	(footprint ""
		(layer "F.Cu")
		(at 198.76135 -148.91131 180)
		(property "Reference" "C220"
			(at 0 0 180)
			(layer "F.SilkS")
			(hide yes)
			(effects
				(font
					(size 1.27 1.27)
				)
			)
		)
		(property "Value" ""
			(at 0 0 180)
			(layer "F.Fab")
			(effects
				(font
					(size 1.27 1.27)
				)
			)
		)
		(duplicate_pad_numbers_are_jumpers no)
		(fp_line
			(start 0.299974 0.150114)
			(end -0.299974 0.150114)
			(stroke
				(width 0.1)
				(type default)
			)
			(layer "F.Fab")
		)
		(fp_line
			(start 0.299974 -0.150114)
			(end 0.299974 0.150114)
			(stroke
				(width 0.1)
				(type default)
			)
			(layer "F.Fab")
		)
		(fp_line
			(start -0.299974 0.150114)
			(end -0.299974 -0.150114)
			(stroke
				(width 0.1)
				(type default)
			)
			(layer "F.Fab")
		)
		(fp_line
			(start -0.299974 -0.150114)
			(end 0.299974 -0.150114)
			(stroke
				(width 0.1)
				(type default)
			)
			(layer "F.Fab")
		)
		(pad "1" smd rect
			(at -0.2667 0 180)
			(size 0.3048 0.381)
			(layers "F.Cu" "F.Mask" "F.Paste")
			(net "P5E_PEX1_STN0_TX_DP<11>")
		)
		(pad "2" smd rect
			(at 0.2667 0 180)
			(size 0.3048 0.381)
			(layers "F.Cu" "F.Mask" "F.Paste")
			(net "P5E_PEX1_STN0_TX_C_DP<11>")
		)
	)
)
